# BARRELEYE-G2-SXM2 RISER BOARD-EVT-X00-BOM-X01-20171102_Final.xls.xlsx — Summary (bom)
| PLATFORM SOURCING AND PSL COMPLIANCE |  |  |  |  |  |  |  |  |  |
| Platform Name: |  |  |  |  |  |  |  |  |  |
| REVISION HISTORY |  |  |  |  |  |  |  |  |  |
| BOM Revision: | ECR # | Revision Description | Originator | Date |  |  |  |  |  |
| X01 |  |  |  | 43041 |  |  |  |  |  |
| Commodity Sourcing | # of components (X00 BOM) | % of Total | # of components (X01 BOM) | % of Total | # of components (X02 BOM) | % of Total | # of components (RTS) | % of Total | Risk Mitigation Plans in Place |
| Sole Source |  |  | 0 |  |  |  |  |  |  |
| Single Source |  |  | 18 | 0.3333333333 |  |  |  |  |  |
| Multiple |  |  | 36 | 0.6666666667 |  |  |  |  | NA |
| Total |  |  | 54 | 1 |  |  |  |  | NA |
|  |  | # of components | # of components aligned with Customer PSL* | % PSL alignment |  |  |  |  |  |
| Class 1 (Customer Managed) |  |  |  |  |  |  |  |  |  |
| Class 2 (ODM Managed to Customer PSL) |  |  |  |  |  |  |  |  |  |
| All other components(ODM Managed to ODM PSL) |  |  |  |  |  |  |  |  |  |
| *RFQ and/or Contract will list requirements for complying with Customer's PSL |  |  |  |  |  |  |  |  |  |
| Reference for quotation |  |  |  |  |  |  |  |  |  |
